# SCM (Grand Teton) — schematic netlist excerpt (pin names and nets, part order shuffled) for the footprints in the layout excerpt that follows; sources: Cadence DE-HDL packaged netlist, KiCad conversion of 12092022_DA0F0TMDCD0_F0T_Management_Board_D_brd_V3_OCP.brd

U24  74LVC2G07DW7  74LVC2G07DW-7 IC  pkg SOT363_0-65_2X1-25XC  page 30
  \1a\  = UART_BMC_5_TXD_BUF1_R
  GND  = GND
  \2a\  = UART_BMC_5_RXD_BUF
  \2y\  = UART_BMC_5_RXD_BUF_R
  VCC  = P3V3_AUX
  \1y\  = UART_BMC_5_TXD_BUF

C314  Q_CAP  0.1UF 25V 10% X7R  pkg 0402  page 15 : A = PGPPA_BMC_AUX_SENSOR ; B = GND

(kicad_pcb
	(version 20260206)
	(generator "pcbnew")
	(generator_version "10.0")
	(general
		(thickness 1.6)
		(legacy_teardrops no)
	)
	(paper "A4")
	(title_block
		(title "12092022_DA0F0TMDCD0_F0T_Management_Board_D_brd_V3_OCP.brd")
		(comment 1 "Grand Teton / footprints 1160-1161 of 1440")
	)
	(layers
		(0 "F.Cu" signal "TOP")
		(4 "In1.Cu" signal "GND")
		(6 "In2.Cu" signal "IN1")
		(8 "In3.Cu" signal "GND1")
		(10 "In4.Cu" signal "IN2")
		(12 "In5.Cu" signal "VCC")
		(14 "In6.Cu" signal "VCC1")
		(16 "In7.Cu" signal "IN3")
		(18 "In8.Cu" signal "GND2")
		(20 "In9.Cu" signal "IN4")
		(22 "In10.Cu" signal "GND3")
		(2 "B.Cu" signal "BOTTOM")
		(9 "F.Adhes" user "F.Adhesive")
		(11 "B.Adhes" user "B.Adhesive")
		(13 "F.Paste" user "Package Geometry/Pastemask Top")
		(15 "B.Paste" user "Package Geometry/Pastemask Bottom")
		(5 "F.SilkS" user "Ref Des/Silkscreen Top")
		(7 "B.SilkS" user "Ref Des/Silkscreen Bottom")
		(1 "F.Mask" user "Board Geometry/Soldermask Top")
		(3 "B.Mask" user "Board Geometry/Soldermask Bottom")
		(17 "Dwgs.User" user "User.Drawings")
		(19 "Cmts.User" user "User.Comments")
		(21 "Eco1.User" user "User.Eco1")
		(23 "Eco2.User" user "User.Eco2")
		(25 "Edge.Cuts" user "Board Geometry/Outline")
		(27 "Margin" user)
		(31 "F.CrtYd" user "Package Geometry/Place Bound Top")
		(29 "B.CrtYd" user "Package Geometry/Place Bound Bottom")
		(35 "F.Fab" user "Ref Des/Assembly Top")
		(33 "B.Fab" user "Ref Des/Assembly Bottom")
	)
	(footprint ""
		(layer "B.Cu")
		(at 7.9756 -27.7368)
		(property "Reference" "U24"
			(at 0.9652 -1.80213 0)
			(unlocked yes)
			(layer "B.SilkS")
			(effects
				(font
					(size 0.7874 0.5842)
					(thickness 0.1524)
				)
				(justify left mirror)
			)
		)
		(property "Value" ""
			(at 0 0 0)
			(layer "B.Fab")
			(effects
				(font
					(size 1.27 1.27)
				)
				(justify mirror)
			)
		)
		(duplicate_pad_numbers_are_jumpers no)
		(fp_line
			(start -1.38176 -1.100074)
			(end -0.592074 -1.100074)
			(stroke
				(width 0.1524)
				(type default)
			)
			(layer "B.SilkS")
		)
		(fp_line
			(start -1.38176 1.100074)
			(end -1.38176 -1.100074)
			(stroke
				(width 0.1524)
				(type default)
			)
			(layer "B.SilkS")
		)
		(fp_line
			(start -0.592074 -1.100074)
			(end 0 -0.508)
			(stroke
				(width 0.1524)
				(type default)
			)
			(layer "B.SilkS")
		)
		(fp_line
			(start 0 -0.508)
			(end 0.592074 -1.100074)
			(stroke
				(width 0.1524)
				(type default)
			)
			(layer "B.SilkS")
		)
		(fp_line
			(start 0.592074 -1.100074)
			(end 1.38176 -1.100074)
			(stroke
				(width 0.1524)
				(type default)
			)
			(layer "B.SilkS")
		)
		(fp_line
			(start 1.38176 -1.100074)
			(end 1.38176 1.100074)
			(stroke
				(width 0.1524)
				(type default)
			)
			(layer "B.SilkS")
		)
		(fp_line
			(start 1.38176 1.100074)
			(end -1.38176 1.100074)
			(stroke
				(width 0.1524)
				(type default)
			)
			(layer "B.SilkS")
		)
		(fp_poly
			(pts
				(xy 1.9431 -0.870204) (xy 1.50241 -0.649986) (xy 1.9431 -0.429768)
			)
			(stroke
				(width 0)
				(type default)
			)
			(fill yes)
			(layer "B.SilkS")
		)
		(fp_line
			(start -0.674878 -1.100074)
			(end 0.674878 -1.100074)
			(stroke
				(width 0.1)
				(type default)
			)
			(layer "B.Fab")
		)
		(fp_line
			(start -0.674878 1.100074)
			(end -0.674878 -1.100074)
			(stroke
				(width 0.1)
				(type default)
			)
			(layer "B.Fab")
		)
		(fp_line
			(start 0.674878 -1.100074)
			(end 0.674878 1.100074)
			(stroke
				(width 0.1)
				(type default)
			)
			(layer "B.Fab")
		)
		(fp_line
			(start 0.674878 1.100074)
			(end -0.674878 1.100074)
			(stroke
				(width 0.1)
				(type default)
			)
			(layer "B.Fab")
		)
		(fp_poly
			(pts
				(xy 1.9431 -0.870204) (xy 1.50241 -0.649986) (xy 1.9431 -0.429768)
			)
			(stroke
				(width 0)
				(type default)
			)
			(fill yes)
			(layer "B.Fab")
		)
		(pad "1" smd rect
			(at 0.94996 -0.649986 270)
			(size 0.4318 0.6096)
			(layers "B.Cu" "B.Mask" "B.Paste")
			(net "UART_BMC_5_TXD_BUF1_R")
		)
		(pad "2" smd rect
			(at 0.94996 0 270)
			(size 0.4318 0.6096)
			(layers "B.Cu" "B.Mask" "B.Paste")
			(net "GND")
		)
		(pad "3" smd rect
			(at 0.94996 0.649986 270)
			(size 0.4318 0.6096)
			(layers "B.Cu" "B.Mask" "B.Paste")
			(net "UART_BMC_5_RXD_BUF")
		)
		(pad "4" smd rect
			(at -0.94996 0.649986 270)
			(size 0.4318 0.6096)
			(layers "B.Cu" "B.Mask" "B.Paste")
			(net "UART_BMC_5_RXD_BUF_R")
		)
		(pad "5" smd rect
			(at -0.94996 0 270)
			(size 0.4318 0.6096)
			(layers "B.Cu" "B.Mask" "B.Paste")
			(net "P3V3_AUX")
		)
		(pad "6" smd rect
			(at -0.94996 -0.649986 270)
			(size 0.4318 0.6096)
			(layers "B.Cu" "B.Mask" "B.Paste")
			(net "UART_BMC_5_TXD_BUF")
		)
	)
	(footprint ""
		(layer "B.Cu")
		(at 58.890662 -71.082662)
		(property "Reference" "C314"
			(at 0 0 0)
			(layer "B.SilkS")
			(hide yes)
			(effects
				(font
					(size 1.27 1.27)
				)
				(justify mirror)
			)
		)
		(property "Value" ""
			(at 0 0 0)
			(layer "B.Fab")
			(effects
				(font
					(size 1.27 1.27)
				)
				(justify mirror)
			)
		)
		(duplicate_pad_numbers_are_jumpers no)
		(fp_line
			(start -0.7874 -0.4064)
			(end -0.7874 0.4064)
			(stroke
				(width 0.1524)
				(type default)
			)
			(layer "B.SilkS")
		)
		(fp_line
			(start -0.7874 0.4064)
			(end 0.7874 0.4064)
			(stroke
				(width 0.1524)
				(type default)
			)
			(layer "B.SilkS")
		)
		(fp_line
			(start 0.7874 -0.4064)
			(end -0.7874 -0.4064)
			(stroke
				(width 0.1524)
				(type default)
			)
			(layer "B.SilkS")
		)
		(fp_line
			(start 0.7874 0.4064)
			(end 0.7874 -0.4064)
			(stroke
				(width 0.1524)
				(type default)
			)
			(layer "B.SilkS")
		)
		(fp_line
			(start -0.67945 -0.3048)
			(end -0.67945 0.3048)
			(stroke
				(width 0.1)
				(type default)
			)
			(layer "B.Fab")
		)
		(fp_line
			(start -0.67945 0.3048)
			(end -0.120396 0.3048)
			(stroke
				(width 0.1)
				(type default)
			)
			(layer "B.Fab")
		)
		(fp_line
			(start -0.12065 -0.3048)
			(end -0.67945 -0.3048)
			(stroke
				(width 0.1)
				(type default)
			)
			(layer "B.Fab")
		)
		(fp_line
			(start -0.12065 -0.2794)
			(end -0.12065 -0.3048)
			(stroke
				(width 0.1)
				(type default)
			)
			(layer "B.Fab")
		)
		(fp_line
			(start -0.120396 0.2794)
			(end 0.12065 0.2794)
			(stroke
				(width 0.1)
				(type default)
			)
			(layer "B.Fab")
		)
		(fp_line
			(start -0.120396 0.3048)
			(end -0.120396 0.2794)
			(stroke
				(width 0.1)
				(type default)
			)
			(layer "B.Fab")
		)
		(fp_line
			(start 0.12065 -0.305054)
			(end 0.12065 -0.2794)
			(stroke
				(width 0.1)
				(type default)
			)
			(layer "B.Fab")
		)
		(fp_line
			(start 0.12065 -0.2794)
			(end -0.12065 -0.2794)
			(stroke
				(width 0.1)
				(type default)
			)
			(layer "B.Fab")
		)
		(fp_line
			(start 0.12065 0.2794)
			(end 0.12065 0.3048)
			(stroke
				(width 0.1)
				(type default)
			)
			(layer "B.Fab")
		)
		(fp_line
			(start 0.12065 0.3048)
			(end 0.67945 0.3048)
			(stroke
				(width 0.1)
				(type default)
			)
			(layer "B.Fab")
		)
		(fp_line
			(start 0.67945 -0.305054)
			(end 0.12065 -0.305054)
			(stroke
				(width 0.1)
				(type default)
			)
			(layer "B.Fab")
		)
		(fp_line
			(start 0.67945 0.3048)
			(end 0.67945 -0.305054)
			(stroke
				(width 0.1)
				(type default)
			)
			(layer "B.Fab")
		)
		(pad "1" smd circle
			(at 0.40005 0 180)
			(size 0 0)
			(layers "B.Cu" "B.Mask" "B.Paste")
			(net "PGPPA_BMC_AUX_SENSOR")
		)
		(pad "2" smd circle
			(at -0.40005 0 180)
			(size 0 0)
			(layers "B.Cu" "B.Mask" "B.Paste")
			(net "GND")
		)
	)
)
